(kicad_pcb
	(version 20260206)
	(generator "pcbnew")
	(generator_version "10.0")
	(general
		(thickness 1.6)
		(legacy_teardrops no)
	)
	(paper "A4")
	(title_block
		(title "03242023_DA0F0TMBIJ0_F0T_Motherboard_J_brd_V01_OCP.brd")
		(comment 1 "Grand Teton / footprints 60-65 of 6105")
	)
	(layers
		(0 "F.Cu" signal "TOP")
		(4 "In1.Cu" signal "GND")
		(6 "In2.Cu" signal "IN1")
		(8 "In3.Cu" signal "GND1")
		(10 "In4.Cu" signal "IN2")
		(12 "In5.Cu" signal "GND2")
		(14 "In6.Cu" signal "IN3")
		(16 "In7.Cu" signal "GND3")
		(18 "In8.Cu" signal "VCC")
		(20 "In9.Cu" signal "VCC1")
		(22 "In10.Cu" signal "GND4")
		(24 "In11.Cu" signal "IN4")
		(26 "In12.Cu" signal "GND5")
		(28 "In13.Cu" signal "IN5")
		(30 "In14.Cu" signal "GND6")
		(32 "In15.Cu" signal "IN6")
		(34 "In16.Cu" signal "GND7")
		(2 "B.Cu" signal "BOTTOM")
		(9 "F.Adhes" user "F.Adhesive")
		(11 "B.Adhes" user "B.Adhesive")
		(13 "F.Paste" user "Package Geometry/Pastemask Top")
		(15 "B.Paste" user "Package Geometry/Pastemask Bottom")
		(5 "F.SilkS" user "Ref Des/Silkscreen Top")
		(7 "B.SilkS" user "Ref Des/Silkscreen Bottom")
		(1 "F.Mask" user "Board Geometry/Soldermask Top")
		(3 "B.Mask" user "Board Geometry/Soldermask Bottom")
		(17 "Dwgs.User" user "User.Drawings")
		(19 "Cmts.User" user "User.Comments")
		(21 "Eco1.User" user "User.Eco1")
		(23 "Eco2.User" user "User.Eco2")
		(25 "Edge.Cuts" user "Board Geometry/Outline")
		(27 "Margin" user)
		(31 "F.CrtYd" user "Package Geometry/Place Bound Top")
		(29 "B.CrtYd" user "Package Geometry/Place Bound Bottom")
		(35 "F.Fab" user "Ref Des/Assembly Top")
		(33 "B.Fab" user "Ref Des/Assembly Bottom")
	)
	(footprint ""
		(layer "F.Cu")
		(at 182.964582 -425.831)
		(property "Reference" "R4769"
			(at 0 0 0)
			(layer "F.SilkS")
			(hide yes)
			(effects
				(font
					(size 1.27 1.27)
				)
			)
		)
		(property "Value" ""
			(at 0 0 0)
			(layer "F.Fab")
			(effects
				(font
					(size 1.27 1.27)
				)
			)
		)
		(duplicate_pad_numbers_are_jumpers no)
		(fp_line
			(start -0.7874 -0.4064)
			(end 0.7874 -0.4064)
			(stroke
				(width 0.1524)
				(type default)
			)
			(layer "F.SilkS")
		)
		(fp_line
			(start -0.7874 0.4064)
			(end -0.7874 -0.4064)
			(stroke
				(width 0.1524)
				(type default)
			)
			(layer "F.SilkS")
		)
		(fp_line
			(start 0.7874 -0.4064)
			(end 0.7874 0.4064)
			(stroke
				(width 0.1524)
				(type default)
			)
			(layer "F.SilkS")
		)
		(fp_line
			(start 0.7874 0.4064)
			(end -0.7874 0.4064)
			(stroke
				(width 0.1524)
				(type default)
			)
			(layer "F.SilkS")
		)
		(fp_line
			(start -0.67945 -0.305054)
			(end -0.12065 -0.305054)
			(stroke
				(width 0.1)
				(type default)
			)
			(layer "F.Fab")
		)
		(fp_line
			(start -0.67945 0.3048)
			(end -0.67945 -0.305054)
			(stroke
				(width 0.1)
				(type default)
			)
			(layer "F.Fab")
		)
		(fp_line
			(start -0.12065 -0.305054)
			(end -0.12065 -0.2794)
			(stroke
				(width 0.1)
				(type default)
			)
			(layer "F.Fab")
		)
		(fp_line
			(start -0.12065 -0.2794)
			(end 0.12065 -0.2794)
			(stroke
				(width 0.1)
				(type default)
			)
			(layer "F.Fab")
		)
		(fp_line
			(start -0.12065 0.2794)
			(end -0.12065 0.3048)
			(stroke
				(width 0.1)
				(type default)
			)
			(layer "F.Fab")
		)
		(fp_line
			(start -0.12065 0.3048)
			(end -0.67945 0.3048)
			(stroke
				(width 0.1)
				(type default)
			)
			(layer "F.Fab")
		)
		(fp_line
			(start 0.120396 0.2794)
			(end -0.12065 0.2794)
			(stroke
				(width 0.1)
				(type default)
			)
			(layer "F.Fab")
		)
		(fp_line
			(start 0.120396 0.3048)
			(end 0.120396 0.2794)
			(stroke
				(width 0.1)
				(type default)
			)
			(layer "F.Fab")
		)
		(fp_line
			(start 0.12065 -0.3048)
			(end 0.67945 -0.3048)
			(stroke
				(width 0.1)
				(type default)
			)
			(layer "F.Fab")
		)
		(fp_line
			(start 0.12065 -0.2794)
			(end 0.12065 -0.3048)
			(stroke
				(width 0.1)
				(type default)
			)
			(layer "F.Fab")
		)
		(fp_line
			(start 0.67945 -0.3048)
			(end 0.67945 0.3048)
			(stroke
				(width 0.1)
				(type default)
			)
			(layer "F.Fab")
		)
		(fp_line
			(start 0.67945 0.3048)
			(end 0.120396 0.3048)
			(stroke
				(width 0.1)
				(type default)
			)
			(layer "F.Fab")
		)
		(pad "1" smd circle
			(at -0.40005 0)
			(size 0 0)
			(layers "F.Cu" "F.Mask" "F.Paste")
			(net "FM_PDB_BUF_EN_R")
		)
		(pad "2" smd circle
			(at 0.40005 0)
			(size 0 0)
			(layers "F.Cu" "F.Mask" "F.Paste")
			(net "GND")
		)
	)
	(footprint ""
		(layer "F.Cu")
		(at 364.2868 -350.357948 90)
		(property "Reference" "PC2345"
			(at 0 0 90)
			(layer "F.SilkS")
			(hide yes)
			(effects
				(font
					(size 1.27 1.27)
				)
			)
		)
		(property "Value" ""
			(at 0 0 90)
			(layer "F.Fab")
			(effects
				(font
					(size 1.27 1.27)
				)
			)
		)
		(duplicate_pad_numbers_are_jumpers no)
		(fp_line
			(start -3.400044 1.249934)
			(end 3.400044 1.249934)
			(stroke
				(width 0.1524)
				(type default)
			)
			(layer "F.SilkS")
		)
		(fp_circle
			(center 0 1.249934)
			(end 0 4.649978)
			(stroke
				(width 0.1524)
				(type default)
			)
			(fill no)
			(layer "F.SilkS")
		)
		(fp_poly
			(pts
				(arc
					(start -3.400044 1.249934)
					(mid 0 4.649978)
					(end 3.400044 1.249934)
				)
			)
			(stroke
				(width 0)
				(type default)
			)
			(fill yes)
			(layer "F.SilkS")
		)
		(fp_circle
			(center 0 1.249934)
			(end 0 4.649978)
			(stroke
				(width 0.1)
				(type default)
			)
			(fill no)
			(layer "F.Fab")
		)
		(pad "1" thru_hole rect
			(at 0 0 90)
			(size 1.524 1.524)
			(drill 1.016)
			(layers "*.Cu" "*.Mask")
			(remove_unused_layers no)
			(net "SW_P12V_PVCCIN_CPU0_FLT")
			(clearance 0)
			(padstack
				(mode front_inner_back)
				(layer "Inner"
					(shape circle)
					(size 1.524 1.524)
					(clearance 0)
				)
				(layer "B.Cu"
					(shape rect)
					(size 1.524 1.524)
					(clearance 0)
				)
			)
		)
		(pad "2" thru_hole circle
			(at 0 2.500122 90)
			(size 1.524 1.524)
			(drill 1.016)
			(layers "*.Cu" "*.Mask")
			(remove_unused_layers no)
			(net "GND")
			(clearance 0)
		)
	)
	(footprint ""
		(layer "F.Cu")
		(at 439.37174 -100.27158 90)
		(property "Reference" "R4746"
			(at 0 0 90)
			(layer "F.SilkS")
			(hide yes)
			(effects
				(font
					(size 1.27 1.27)
				)
			)
		)
		(property "Value" ""
			(at 0 0 90)
			(layer "F.Fab")
			(effects
				(font
					(size 1.27 1.27)
				)
			)
		)
		(duplicate_pad_numbers_are_jumpers no)
		(fp_line
			(start 0.7874 -0.4064)
			(end 0.7874 0.4064)
			(stroke
				(width 0.1524)
				(type default)
			)
			(layer "F.SilkS")
		)
		(fp_line
			(start -0.7874 -0.4064)
			(end 0.7874 -0.4064)
			(stroke
				(width 0.1524)
				(type default)
			)
			(layer "F.SilkS")
		)
		(fp_line
			(start 0.7874 0.4064)
			(end -0.7874 0.4064)
			(stroke
				(width 0.1524)
				(type default)
			)
			(layer "F.SilkS")
		)
		(fp_line
			(start -0.7874 0.4064)
			(end -0.7874 -0.4064)
			(stroke
				(width 0.1524)
				(type default)
			)
			(layer "F.SilkS")
		)
		(fp_line
			(start -0.12065 -0.305054)
			(end -0.12065 -0.2794)
			(stroke
				(width 0.1)
				(type default)
			)
			(layer "F.Fab")
		)
		(fp_line
			(start -0.67945 -0.305054)
			(end -0.12065 -0.305054)
			(stroke
				(width 0.1)
				(type default)
			)
			(layer "F.Fab")
		)
		(fp_line
			(start 0.67945 -0.3048)
			(end 0.67945 0.3048)
			(stroke
				(width 0.1)
				(type default)
			)
			(layer "F.Fab")
		)
		(fp_line
			(start 0.12065 -0.3048)
			(end 0.67945 -0.3048)
			(stroke
				(width 0.1)
				(type default)
			)
			(layer "F.Fab")
		)
		(fp_line
			(start 0.12065 -0.2794)
			(end 0.12065 -0.3048)
			(stroke
				(width 0.1)
				(type default)
			)
			(layer "F.Fab")
		)
		(fp_line
			(start -0.12065 -0.2794)
			(end 0.12065 -0.2794)
			(stroke
				(width 0.1)
				(type default)
			)
			(layer "F.Fab")
		)
		(fp_line
			(start 0.120396 0.2794)
			(end -0.12065 0.2794)
			(stroke
				(width 0.1)
				(type default)
			)
			(layer "F.Fab")
		)
		(fp_line
			(start -0.12065 0.2794)
			(end -0.12065 0.3048)
			(stroke
				(width 0.1)
				(type default)
			)
			(layer "F.Fab")
		)
		(fp_line
			(start 0.67945 0.3048)
			(end 0.120396 0.3048)
			(stroke
				(width 0.1)
				(type default)
			)
			(layer "F.Fab")
		)
		(fp_line
			(start 0.120396 0.3048)
			(end 0.120396 0.2794)
			(stroke
				(width 0.1)
				(type default)
			)
			(layer "F.Fab")
		)
		(fp_line
			(start -0.12065 0.3048)
			(end -0.67945 0.3048)
			(stroke
				(width 0.1)
				(type default)
			)
			(layer "F.Fab")
		)
		(fp_line
			(start -0.67945 0.3048)
			(end -0.67945 -0.305054)
			(stroke
				(width 0.1)
				(type default)
			)
			(layer "F.Fab")
		)
		(pad "1" smd circle
			(at -0.40005 0 90)
			(size 0 0)
			(layers "F.Cu" "F.Mask" "F.Paste")
			(net "HP_LVC3_OCP_V3_1_PWRGD_R")
		)
		(pad "2" smd circle
			(at 0.40005 0 90)
			(size 0 0)
			(layers "F.Cu" "F.Mask" "F.Paste")
			(net "HP_LVC3_OCP_V3_1_PWRGD_R2")
		)
	)
	(footprint ""
		(layer "F.Cu")
		(at 63.194438 -28.382722)
		(property "Reference" "R3848"
			(at 0 0 0)
			(layer "F.SilkS")
			(hide yes)
			(effects
				(font
					(size 1.27 1.27)
				)
			)
		)
		(property "Value" ""
			(at 0 0 0)
			(layer "F.Fab")
			(effects
				(font
					(size 1.27 1.27)
				)
			)
		)
		(duplicate_pad_numbers_are_jumpers no)
		(fp_line
			(start -0.7874 -0.4064)
			(end 0.7874 -0.4064)
			(stroke
				(width 0.1524)
				(type default)
			)
			(layer "F.SilkS")
		)
		(fp_line
			(start -0.7874 0.4064)
			(end -0.7874 -0.4064)
			(stroke
				(width 0.1524)
				(type default)
			)
			(layer "F.SilkS")
		)
		(fp_line
			(start 0.7874 -0.4064)
			(end 0.7874 0.4064)
			(stroke
				(width 0.1524)
				(type default)
			)
			(layer "F.SilkS")
		)
		(fp_line
			(start 0.7874 0.4064)
			(end -0.7874 0.4064)
			(stroke
				(width 0.1524)
				(type default)
			)
			(layer "F.SilkS")
		)
		(fp_line
			(start -0.67945 -0.305054)
			(end -0.12065 -0.305054)
			(stroke
				(width 0.1)
				(type default)
			)
			(layer "F.Fab")
		)
		(fp_line
			(start -0.67945 0.3048)
			(end -0.67945 -0.305054)
			(stroke
				(width 0.1)
				(type default)
			)
			(layer "F.Fab")
		)
		(fp_line
			(start -0.12065 -0.305054)
			(end -0.12065 -0.2794)
			(stroke
				(width 0.1)
				(type default)
			)
			(layer "F.Fab")
		)
		(fp_line
			(start -0.12065 -0.2794)
			(end 0.12065 -0.2794)
			(stroke
				(width 0.1)
				(type default)
			)
			(layer "F.Fab")
		)
		(fp_line
			(start -0.12065 0.2794)
			(end -0.12065 0.3048)
			(stroke
				(width 0.1)
				(type default)
			)
			(layer "F.Fab")
		)
		(fp_line
			(start -0.12065 0.3048)
			(end -0.67945 0.3048)
			(stroke
				(width 0.1)
				(type default)
			)
			(layer "F.Fab")
		)
		(fp_line
			(start 0.120396 0.2794)
			(end -0.12065 0.2794)
			(stroke
				(width 0.1)
				(type default)
			)
			(layer "F.Fab")
		)
		(fp_line
			(start 0.120396 0.3048)
			(end 0.120396 0.2794)
			(stroke
				(width 0.1)
				(type default)
			)
			(layer "F.Fab")
		)
		(fp_line
			(start 0.12065 -0.3048)
			(end 0.67945 -0.3048)
			(stroke
				(width 0.1)
				(type default)
			)
			(layer "F.Fab")
		)
		(fp_line
			(start 0.12065 -0.2794)
			(end 0.12065 -0.3048)
			(stroke
				(width 0.1)
				(type default)
			)
			(layer "F.Fab")
		)
		(fp_line
			(start 0.67945 -0.3048)
			(end 0.67945 0.3048)
			(stroke
				(width 0.1)
				(type default)
			)
			(layer "F.Fab")
		)
		(fp_line
			(start 0.67945 0.3048)
			(end 0.120396 0.3048)
			(stroke
				(width 0.1)
				(type default)
			)
			(layer "F.Fab")
		)
		(pad "1" smd circle
			(at -0.40005 0)
			(size 0 0)
			(layers "F.Cu" "F.Mask" "F.Paste")
			(net "P3V3_AUX")
		)
		(pad "2" smd circle
			(at 0.40005 0)
			(size 0 0)
			(layers "F.Cu" "F.Mask" "F.Paste")
			(net "HP_LVC3_OCP_V3_2_P12V_PWRGD")
		)
	)
	(footprint ""
		(layer "F.Cu")
		(at 192.898268 -426.355002)
		(property "Reference" "U290"
			(at -1.524508 2.771902 0)
			(unlocked yes)
			(layer "F.SilkS")
			(effects
				(font
					(size 0.7874 0.5842)
					(thickness 0.1524)
				)
				(justify left)
			)
		)
		(property "Value" ""
			(at 0 0 0)
			(layer "F.Fab")
			(effects
				(font
					(size 1.27 1.27)
				)
			)
		)
		(duplicate_pad_numbers_are_jumpers no)
		(fp_line
			(start -1.603248 -1.500124)
			(end 1.603248 -1.500124)
			(stroke
				(width 0.1524)
				(type default)
			)
			(layer "F.SilkS")
		)
		(fp_line
			(start -1.603248 1.500124)
			(end -1.603248 -1.500124)
			(stroke
				(width 0.1524)
				(type default)
			)
			(layer "F.SilkS")
		)
		(fp_line
			(start 1.603248 -1.500124)
			(end 1.603248 1.500124)
			(stroke
				(width 0.1524)
				(type default)
			)
			(layer "F.SilkS")
		)
		(fp_line
			(start 1.603248 1.500124)
			(end -1.603248 1.500124)
			(stroke
				(width 0.1524)
				(type default)
			)
			(layer "F.SilkS")
		)
		(fp_line
			(start -1.249934 -1.169924)
			(end -1.249934 -0.729996)
			(stroke
				(width 0.1)
				(type default)
			)
			(layer "F.Fab")
		)
		(fp_line
			(start -1.249934 -0.729996)
			(end -0.6985 -0.729996)
			(stroke
				(width 0.1)
				(type default)
			)
			(layer "F.Fab")
		)
		(fp_line
			(start -1.249934 0.729996)
			(end -1.249934 1.169924)
			(stroke
				(width 0.1)
				(type default)
			)
			(layer "F.Fab")
		)
		(fp_line
			(start -1.249934 1.169924)
			(end -0.700024 1.169924)
			(stroke
				(width 0.1)
				(type default)
			)
			(layer "F.Fab")
		)
		(fp_line
			(start -0.700024 -1.500124)
			(end -0.700024 -1.169924)
			(stroke
				(width 0.1)
				(type default)
			)
			(layer "F.Fab")
		)
		(fp_line
			(start -0.700024 -1.169924)
			(end -1.249934 -1.169924)
			(stroke
				(width 0.1)
				(type default)
			)
			(layer "F.Fab")
		)
		(fp_line
			(start -0.700024 1.169924)
			(end -0.700024 1.500124)
			(stroke
				(width 0.1)
				(type default)
			)
			(layer "F.Fab")
		)
		(fp_line
			(start -0.700024 1.500124)
			(end 0.700024 1.500124)
			(stroke
				(width 0.1)
				(type default)
			)
			(layer "F.Fab")
		)
		(fp_line
			(start -0.6985 -0.729996)
			(end -0.6985 0.729996)
			(stroke
				(width 0.1)
				(type default)
			)
			(layer "F.Fab")
		)
		(fp_line
			(start -0.6985 0.729996)
			(end -1.249934 0.729996)
			(stroke
				(width 0.1)
				(type default)
			)
			(layer "F.Fab")
		)
		(fp_line
			(start 0.700024 -1.500124)
			(end -0.700024 -1.500124)
			(stroke
				(width 0.1)
				(type default)
			)
			(layer "F.Fab")
		)
		(fp_line
			(start 0.700024 -0.219964)
			(end 0.700024 -1.500124)
			(stroke
				(width 0.1)
				(type default)
			)
			(layer "F.Fab")
		)
		(fp_line
			(start 0.700024 0.219964)
			(end 1.249934 0.219964)
			(stroke
				(width 0.1)
				(type default)
			)
			(layer "F.Fab")
		)
		(fp_line
			(start 0.700024 1.500124)
			(end 0.700024 0.219964)
			(stroke
				(width 0.1)
				(type default)
			)
			(layer "F.Fab")
		)
		(fp_line
			(start 1.249934 -0.219964)
			(end 0.700024 -0.219964)
			(stroke
				(width 0.1)
				(type default)
			)
			(layer "F.Fab")
		)
		(fp_line
			(start 1.249934 0.219964)
			(end 1.249934 -0.219964)
			(stroke
				(width 0.1)
				(type default)
			)
			(layer "F.Fab")
		)
		(fp_rect
			(start 0.700024 1.500124)
			(end -0.700024 -1.500124)
			(stroke
				(width 0)
				(type default)
			)
			(fill no)
			(layer "F.Fab")
		)
		(pad "D" smd rect
			(at 0.999998 0 270)
			(size 0.8128 0.9144)
			(layers "F.Cu" "F.Mask" "F.Paste")
			(net "HSC_EN")
		)
		(pad "G" smd rect
			(at -0.999998 -0.94996 270)
			(size 0.8128 0.9144)
			(layers "F.Cu" "F.Mask" "F.Paste")
			(net "PDB_PRSNT_N")
		)
		(pad "S" smd rect
			(at -0.999998 0.94996 270)
			(size 0.8128 0.9144)
			(layers "F.Cu" "F.Mask" "F.Paste")
			(net "GND")
		)
	)
	(footprint ""
		(layer "F.Cu")
		(at 511.924808 2.33172 -90)
		(property "Reference" "X20"
			(at -1.281684 3.260598 90)
			(unlocked yes)
			(layer "F.SilkS")
			(effects
				(font
					(size 0.7874 0.5842)
					(thickness 0.1524)
				)
				(justify left)
			)
		)
		(property "Value" ""
			(at 0 0 270)
			(layer "F.Fab")
			(effects
				(font
					(size 1.27 1.27)
				)
			)
		)
		(property "Device Type" "TP_TDR_4P_FTS_MPKT4_H025P0200_I"
			(at 1.30175 1.27 0)
			(unlocked yes)
			(layer "F.Fab")
			(hide yes)
			(effects
				(font
					(size 0.635 0.4064)
					(thickness 0.1524)
				)
			)
		)
		(property "User Part Number" "TP15"
			(at 1.30175 1.27 0)
			(unlocked yes)
			(layer "Cmts.User")
			(hide yes)
			(effects
				(font
					(size 0.635 0.4064)
					(thickness 0.1524)
				)
			)
		)
		(duplicate_pad_numbers_are_jumpers no)
		(fp_line
			(start 0 3.81)
			(end 2.54 3.81)
			(stroke
				(width 0.1524)
				(type default)
			)
			(layer "F.SilkS")
		)
		(fp_line
			(start 2.54 3.81)
			(end 2.54 3.6703)
			(stroke
				(width 0.1524)
				(type default)
			)
			(layer "F.SilkS")
		)
		(fp_line
			(start 0 3.175)
			(end 0 3.81)
			(stroke
				(width 0.1524)
				(type default)
			)
			(layer "F.SilkS")
		)
		(fp_line
			(start 2.54 1.4097)
			(end 2.54 1.1303)
			(stroke
				(width 0.1524)
				(type default)
			)
			(layer "F.SilkS")
		)
		(fp_line
			(start 0 0.635)
			(end 0 1.905)
			(stroke
				(width 0.1524)
				(type default)
			)
			(layer "F.SilkS")
		)
		(fp_line
			(start 2.54 -1.1303)
			(end 2.54 -1.27)
			(stroke
				(width 0.1524)
				(type default)
			)
			(layer "F.SilkS")
		)
		(fp_line
			(start 0 -1.27)
			(end 0 -0.635)
			(stroke
				(width 0.1524)
				(type default)
			)
			(layer "F.SilkS")
		)
		(fp_line
			(start 2.54 -1.27)
			(end 0 -1.27)
			(stroke
				(width 0.1524)
				(type default)
			)
			(layer "F.SilkS")
		)
		(fp_poly
			(pts
				(xy -1.33604 -0.088392) (xy -2.86004 0.673608) (xy -2.86004 -0.850392)
			)
			(stroke
				(width 0)
				(type default)
			)
			(fill yes)
			(layer "F.SilkS")
		)
		(fp_line
			(start 0 3.81)
			(end 2.54 3.81)
			(stroke
				(width 0.1)
				(type default)
			)
			(layer "F.Fab")
		)
		(fp_line
			(start 2.54 3.81)
			(end 2.54 -1.27)
			(stroke
				(width 0.1)
				(type default)
			)
			(layer "F.Fab")
		)
		(fp_line
			(start 0 -1.27)
			(end 0 3.81)
			(stroke
				(width 0.1)
				(type default)
			)
			(layer "F.Fab")
		)
		(fp_line
			(start 2.54 -1.27)
			(end 0 -1.27)
			(stroke
				(width 0.1)
				(type default)
			)
			(layer "F.Fab")
		)
		(fp_poly
			(pts
				(xy -0.761746 0) (xy -2.285746 -0.762) (xy -2.285746 0.762)
			)
			(stroke
				(width 0)
				(type default)
			)
			(fill yes)
			(layer "F.Fab")
		)
		(pad "1" thru_hole circle
			(at 0 0 270)
			(size 1.0033 1.0033)
			(drill 0.249936)
			(layers "*.Cu" "*.Mask")
			(remove_unused_layers no)
			(net "TDR_DIFF_100_IN1_DN")
			(clearance 0.10795)
			(thermal_gap 0.10795)
			(padstack
				(mode front_inner_back)
				(layer "Inner"
					(shape circle)
					(size 0.8001 0.8001)
					(clearance 0.1524)
				)
				(layer "B.Cu"
					(shape circle)
					(size 1.0033 1.0033)
					(clearance 0.10795)
				)
			)
		)
		(pad "2" thru_hole circle
			(at 2.54 0 270)
			(size 1.9939 1.9939)
			(drill 0.249936)
			(layers "*.Cu" "*.Mask")
			(remove_unused_layers no)
			(net "T1_GND")
			(clearance 0.10795)
			(thermal_gap 0.10795)
			(padstack
				(mode front_inner_back)
				(layer "Inner"
					(shape circle)
					(size 0.8001 0.8001)
					(clearance 0.1524)
				)
				(layer "B.Cu"
					(shape circle)
					(size 1.9939 1.9939)
					(clearance 0.10795)
				)
			)
		)
		(pad "3" thru_hole circle
			(at 2.54 2.54 270)
			(size 1.9939 1.9939)
			(drill 0.249936)
			(layers "*.Cu" "*.Mask")
			(remove_unused_layers no)
			(net "T1_GND")
			(clearance 0.10795)
			(thermal_gap 0.10795)
			(padstack
				(mode front_inner_back)
				(layer "Inner"
					(shape circle)
					(size 0.8001 0.8001)
					(clearance 0.1524)
				)
				(layer "B.Cu"
					(shape circle)
					(size 1.9939 1.9939)
					(clearance 0.10795)
				)
			)
		)
		(pad "4" thru_hole circle
			(at 0 2.54 270)
			(size 1.0033 1.0033)
			(drill 0.249936)
			(layers "*.Cu" "*.Mask")
			(remove_unused_layers no)
			(net "TDR_DIFF_100_IN1_DP")
			(clearance 0.10795)
			(thermal_gap 0.10795)
			(padstack
				(mode front_inner_back)
				(layer "Inner"
					(shape circle)
					(size 0.8001 0.8001)
					(clearance 0.1524)
				)
				(layer "B.Cu"
					(shape circle)
					(size 1.0033 1.0033)
					(clearance 0.10795)
				)
			)
		)
	)
)
